# S9S_MB_2U (Grand Teton) — schematic netlist excerpt (pin names and nets, part order shuffled) for the footprints in the layout excerpt that follows; sources: Cadence DE-HDL packaged netlist, KiCad conversion of 03242023_DA0F0TMBIJ0_F0T_Motherboard_J_brd_V01_OCP.brd

PC1678  Q_CAP  22UF 16V 20% X6S  pkg C0805  page 289 : A = SW_P12V_PVCCFA_EHV_FIVRA_CPU1_L ; B = GND

Q105  MOSFET_NCH_DUAL  NX6008NBKS IC  pkg SOT363XB  page 256
  S1  = GND
  G1  = RST_PLD_CPU1_DRAM_AB_N
  D1  = LED_RST_PLD_CPU1_DRAM_AB_N_D

R1450  Q_RES  10K 1% CHIP  pkg 0402LF  page 204 : A = P3V3_AUX ; B = FM_THROTTLE_N

(kicad_pcb
	(version 20260206)
	(generator "pcbnew")
	(generator_version "10.0")
	(general
		(thickness 1.6)
		(legacy_teardrops no)
	)
	(paper "A4")
	(title_block
		(title "03242023_DA0F0TMBIJ0_F0T_Motherboard_J_brd_V01_OCP.brd")
		(comment 1 "Grand Teton / footprints 2787-2789 of 6105")
	)
	(layers
		(0 "F.Cu" signal "TOP")
		(4 "In1.Cu" signal "GND")
		(6 "In2.Cu" signal "IN1")
		(8 "In3.Cu" signal "GND1")
		(10 "In4.Cu" signal "IN2")
		(12 "In5.Cu" signal "GND2")
		(14 "In6.Cu" signal "IN3")
		(16 "In7.Cu" signal "GND3")
		(18 "In8.Cu" signal "VCC")
		(20 "In9.Cu" signal "VCC1")
		(22 "In10.Cu" signal "GND4")
		(24 "In11.Cu" signal "IN4")
		(26 "In12.Cu" signal "GND5")
		(28 "In13.Cu" signal "IN5")
		(30 "In14.Cu" signal "GND6")
		(32 "In15.Cu" signal "IN6")
		(34 "In16.Cu" signal "GND7")
		(2 "B.Cu" signal "BOTTOM")
		(9 "F.Adhes" user "F.Adhesive")
		(11 "B.Adhes" user "B.Adhesive")
		(13 "F.Paste" user "Package Geometry/Pastemask Top")
		(15 "B.Paste" user "Package Geometry/Pastemask Bottom")
		(5 "F.SilkS" user "Ref Des/Silkscreen Top")
		(7 "B.SilkS" user "Ref Des/Silkscreen Bottom")
		(1 "F.Mask" user "Board Geometry/Soldermask Top")
		(3 "B.Mask" user "Board Geometry/Soldermask Bottom")
		(17 "Dwgs.User" user "User.Drawings")
		(19 "Cmts.User" user "User.Comments")
		(21 "Eco1.User" user "User.Eco1")
		(23 "Eco2.User" user "User.Eco2")
		(25 "Edge.Cuts" user "Board Geometry/Outline")
		(27 "Margin" user)
		(31 "F.CrtYd" user "Package Geometry/Place Bound Top")
		(29 "B.CrtYd" user "Package Geometry/Place Bound Bottom")
		(35 "F.Fab" user "Ref Des/Assembly Top")
		(33 "B.Fab" user "Ref Des/Assembly Bottom")
	)
	(footprint ""
		(layer "F.Cu")
		(at 309.522622 -30.343348 180)
		(property "Reference" "R1450"
			(at 0 0 180)
			(layer "F.SilkS")
			(hide yes)
			(effects
				(font
					(size 1.27 1.27)
				)
			)
		)
		(property "Value" ""
			(at 0 0 180)
			(layer "F.Fab")
			(effects
				(font
					(size 1.27 1.27)
				)
			)
		)
		(duplicate_pad_numbers_are_jumpers no)
		(fp_line
			(start 0.7874 0.4064)
			(end -0.7874 0.4064)
			(stroke
				(width 0.1524)
				(type default)
			)
			(layer "F.SilkS")
		)
		(fp_line
			(start 0.7874 -0.4064)
			(end 0.7874 0.4064)
			(stroke
				(width 0.1524)
				(type default)
			)
			(layer "F.SilkS")
		)
		(fp_line
			(start -0.7874 0.4064)
			(end -0.7874 -0.4064)
			(stroke
				(width 0.1524)
				(type default)
			)
			(layer "F.SilkS")
		)
		(fp_line
			(start -0.7874 -0.4064)
			(end 0.7874 -0.4064)
			(stroke
				(width 0.1524)
				(type default)
			)
			(layer "F.SilkS")
		)
		(fp_line
			(start 0.67945 0.3048)
			(end 0.120396 0.3048)
			(stroke
				(width 0.1)
				(type default)
			)
			(layer "F.Fab")
		)
		(fp_line
			(start 0.67945 -0.3048)
			(end 0.67945 0.3048)
			(stroke
				(width 0.1)
				(type default)
			)
			(layer "F.Fab")
		)
		(fp_line
			(start 0.12065 -0.2794)
			(end 0.12065 -0.3048)
			(stroke
				(width 0.1)
				(type default)
			)
			(layer "F.Fab")
		)
		(fp_line
			(start 0.12065 -0.3048)
			(end 0.67945 -0.3048)
			(stroke
				(width 0.1)
				(type default)
			)
			(layer "F.Fab")
		)
		(fp_line
			(start 0.120396 0.3048)
			(end 0.120396 0.2794)
			(stroke
				(width 0.1)
				(type default)
			)
			(layer "F.Fab")
		)
		(fp_line
			(start 0.120396 0.2794)
			(end -0.12065 0.2794)
			(stroke
				(width 0.1)
				(type default)
			)
			(layer "F.Fab")
		)
		(fp_line
			(start -0.12065 0.3048)
			(end -0.67945 0.3048)
			(stroke
				(width 0.1)
				(type default)
			)
			(layer "F.Fab")
		)
		(fp_line
			(start -0.12065 0.2794)
			(end -0.12065 0.3048)
			(stroke
				(width 0.1)
				(type default)
			)
			(layer "F.Fab")
		)
		(fp_line
			(start -0.12065 -0.2794)
			(end 0.12065 -0.2794)
			(stroke
				(width 0.1)
				(type default)
			)
			(layer "F.Fab")
		)
		(fp_line
			(start -0.12065 -0.305054)
			(end -0.12065 -0.2794)
			(stroke
				(width 0.1)
				(type default)
			)
			(layer "F.Fab")
		)
		(fp_line
			(start -0.67945 0.3048)
			(end -0.67945 -0.305054)
			(stroke
				(width 0.1)
				(type default)
			)
			(layer "F.Fab")
		)
		(fp_line
			(start -0.67945 -0.305054)
			(end -0.12065 -0.305054)
			(stroke
				(width 0.1)
				(type default)
			)
			(layer "F.Fab")
		)
		(pad "1" smd circle
			(at -0.40005 0 180)
			(size 0 0)
			(layers "F.Cu" "F.Mask" "F.Paste")
			(net "P3V3_AUX")
		)
		(pad "2" smd circle
			(at 0.40005 0 180)
			(size 0 0)
			(layers "F.Cu" "F.Mask" "F.Paste")
			(net "FM_THROTTLE_N")
		)
	)
	(footprint ""
		(layer "F.Cu")
		(at 94.045278 -102.509574 180)
		(property "Reference" "Q105"
			(at 3.089656 0.763016 0)
			(unlocked yes)
			(layer "F.SilkS")
			(effects
				(font
					(size 0.7874 0.5842)
					(thickness 0.1524)
				)
			)
		)
		(property "Value" ""
			(at 0 0 180)
			(layer "F.Fab")
			(effects
				(font
					(size 1.27 1.27)
				)
			)
		)
		(duplicate_pad_numbers_are_jumpers no)
		(fp_line
			(start 1.376172 1.199896)
			(end -1.376172 1.199896)
			(stroke
				(width 0.1524)
				(type default)
			)
			(layer "F.SilkS")
		)
		(fp_line
			(start 1.376172 -1.199896)
			(end 1.376172 1.199896)
			(stroke
				(width 0.1524)
				(type default)
			)
			(layer "F.SilkS")
		)
		(fp_line
			(start 0.508 -1.199896)
			(end 1.376172 -1.199896)
			(stroke
				(width 0.1524)
				(type default)
			)
			(layer "F.SilkS")
		)
		(fp_line
			(start 0 -0.762)
			(end 0.508 -1.199896)
			(stroke
				(width 0.1524)
				(type default)
			)
			(layer "F.SilkS")
		)
		(fp_line
			(start -0.508 -1.199896)
			(end 0 -0.762)
			(stroke
				(width 0.1524)
				(type default)
			)
			(layer "F.SilkS")
		)
		(fp_line
			(start -1.376172 1.199896)
			(end -1.376172 -1.199896)
			(stroke
				(width 0.1524)
				(type default)
			)
			(layer "F.SilkS")
		)
		(fp_line
			(start -1.376172 -1.199896)
			(end -0.508 -1.199896)
			(stroke
				(width 0.1524)
				(type default)
			)
			(layer "F.SilkS")
		)
		(fp_poly
			(pts
				(xy -1.4605 -0.7493) (xy -2.2225 -0.3683) (xy -2.2225 -1.1303)
			)
			(stroke
				(width 0)
				(type default)
			)
			(fill yes)
			(layer "F.SilkS")
		)
		(fp_line
			(start 0.674878 1.100074)
			(end -0.674878 1.100074)
			(stroke
				(width 0.1)
				(type default)
			)
			(layer "F.Fab")
		)
		(fp_line
			(start 0.674878 -1.100074)
			(end 0.674878 1.100074)
			(stroke
				(width 0.1)
				(type default)
			)
			(layer "F.Fab")
		)
		(fp_line
			(start -0.674878 1.100074)
			(end -0.674878 -1.100074)
			(stroke
				(width 0.1)
				(type default)
			)
			(layer "F.Fab")
		)
		(fp_line
			(start -0.674878 -1.100074)
			(end 0.674878 -1.100074)
			(stroke
				(width 0.1)
				(type default)
			)
			(layer "F.Fab")
		)
		(fp_poly
			(pts
				(xy -1.4605 -0.7493) (xy -2.2225 -1.1303) (xy -2.2225 -0.3683)
			)
			(stroke
				(width 0)
				(type default)
			)
			(fill yes)
			(layer "F.Fab")
		)
		(pad "1" smd rect
			(at -0.899922 -0.750062 90)
			(size 0.6096 0.6096)
			(layers "F.Cu" "F.Mask" "F.Paste")
			(net "GND")
		)
		(pad "2" smd rect
			(at -0.899922 0 90)
			(size 0.4064 0.6096)
			(layers "F.Cu" "F.Mask" "F.Paste")
			(net "RST_PLD_CPU1_DRAM_AB_N")
		)
		(pad "3" smd rect
			(at -0.899922 0.750062 90)
			(size 0.6096 0.6096)
			(layers "F.Cu" "F.Mask" "F.Paste")
			(net "Net_1467")
		)
		(pad "4" smd rect
			(at 0.899922 0.750062 90)
			(size 0.6096 0.6096)
			(layers "F.Cu" "F.Mask" "F.Paste")
			(net "Net_1469")
		)
		(pad "5" smd rect
			(at 0.899922 0 90)
			(size 0.4064 0.6096)
			(layers "F.Cu" "F.Mask" "F.Paste")
			(net "Net_1468")
		)
		(pad "6" smd rect
			(at 0.899922 -0.750062 90)
			(size 0.6096 0.6096)
			(layers "F.Cu" "F.Mask" "F.Paste")
			(net "LED_RST_PLD_CPU1_DRAM_AB_N_D")
		)
	)
	(footprint ""
		(layer "F.Cu")
		(at 56.349138 -362.656882)
		(property "Reference" "PC1678"
			(at 0 0 0)
			(layer "F.SilkS")
			(hide yes)
			(effects
				(font
					(size 1.27 1.27)
				)
			)
		)
		(property "Value" ""
			(at 0 0 0)
			(layer "F.Fab")
			(effects
				(font
					(size 1.27 1.27)
				)
			)
		)
		(duplicate_pad_numbers_are_jumpers no)
		(fp_line
			(start -1.524 -0.762)
			(end 1.524 -0.762)
			(stroke
				(width 0.1524)
				(type default)
			)
			(layer "F.SilkS")
		)
		(fp_line
			(start -1.524 0.762)
			(end -1.524 -0.762)
			(stroke
				(width 0.1524)
				(type default)
			)
			(layer "F.SilkS")
		)
		(fp_line
			(start 1.524 -0.762)
			(end 1.524 0.762)
			(stroke
				(width 0.1524)
				(type default)
			)
			(layer "F.SilkS")
		)
		(fp_line
			(start 1.524 0.762)
			(end -1.524 0.762)
			(stroke
				(width 0.1524)
				(type default)
			)
			(layer "F.SilkS")
		)
		(fp_line
			(start -1.1049 -0.724916)
			(end -1.1049 0.724916)
			(stroke
				(width 0.1)
				(type default)
			)
			(layer "F.Fab")
		)
		(fp_line
			(start -1.1049 0.724916)
			(end 1.1049 0.724916)
			(stroke
				(width 0.1)
				(type default)
			)
			(layer "F.Fab")
		)
		(fp_line
			(start 1.1049 -0.724916)
			(end -1.1049 -0.724916)
			(stroke
				(width 0.1)
				(type default)
			)
			(layer "F.Fab")
		)
		(fp_line
			(start 1.1049 0.724916)
			(end 1.1049 -0.724916)
			(stroke
				(width 0.1)
				(type default)
			)
			(layer "F.Fab")
		)
		(pad "1" smd rect
			(at -0.889 0 180)
			(size 1.016 1.27)
			(layers "F.Cu" "F.Mask" "F.Paste")
			(net "SW_P12V_PVCCFA_EHV_FIVRA_CPU1_L")
		)
		(pad "2" smd rect
			(at 0.889 0 180)
			(size 1.016 1.27)
			(layers "F.Cu" "F.Mask" "F.Paste")
			(net "GND")
		)
	)
)
